(kicad_pcb
	(version 20241229)
	(generator "pcbnew")
	(generator_version "9.0")
	(general
		(thickness 1.61)
		(legacy_teardrops no)
	)
	(paper "A3")
	(title_block
		(title "RDIMM DDR5 Tester")
		(date "2026-05-21")
		(rev "2.2.0")
		(company "Antmicro")
		(comment 9 "footprints 87-91 of 796")
	)
	(layers
		(0 "F.Cu" signal)
		(4 "In1.Cu" power)
		(6 "In2.Cu" mixed)
		(8 "In3.Cu" power)
		(10 "In4.Cu" mixed)
		(12 "In5.Cu" power)
		(14 "In6.Cu" mixed)
		(16 "In7.Cu" power)
		(18 "In8.Cu" power)
		(20 "In9.Cu" mixed)
		(22 "In10.Cu" power)
		(2 "B.Cu" signal)
		(9 "F.Adhes" user "F.Adhesive")
		(11 "B.Adhes" user "B.Adhesive")
		(13 "F.Paste" user)
		(15 "B.Paste" user)
		(5 "F.SilkS" user "F.Silkscreen")
		(7 "B.SilkS" user "B.Silkscreen")
		(1 "F.Mask" user)
		(3 "B.Mask" user)
		(17 "Dwgs.User" user "User.Drawings")
		(19 "Cmts.User" user "User.Comments")
		(21 "Eco1.User" user "User.Eco1")
		(23 "Eco2.User" user "User.Eco2")
		(25 "Edge.Cuts" user)
		(27 "Margin" user)
		(31 "F.CrtYd" user "F.Courtyard")
		(29 "B.CrtYd" user "B.Courtyard")
		(35 "F.Fab" user)
		(33 "B.Fab" user)
	)
	(footprint "antmicro-footprints:C_0603_1608Metric"
		(layer "F.Cu")
		(at 248.793 156.521 -90)
		(descr "Capacitor SMD 0603")
		(tags "capacitor 0603")
		(property "Reference" "C184"
			(at -1.346 0.968 90)
			(layer "F.SilkS")
			(effects
				(font
					(size 0.7 0.7)
					(thickness 0.15)
				)
				(justify right bottom)
			)
		)
		(property "Value" "C_22u_0603"
			(at -1.42757 1.770288 90)
			(layer "F.Fab")
			(effects
				(font
					(size 0.7 0.7)
					(thickness 0.15)
				)
				(justify right bottom)
			)
		)
		(property "Datasheet" "https://www.murata.com/products/productdetail?partno=GRM188R60J226MEA0%23"
			(at 0 0 270)
			(layer "F.Fab")
			(hide yes)
			(effects
				(font
					(size 1.27 1.27)
					(thickness 0.15)
				)
			)
		)
		(property "Manufacturer" "Murata"
			(at 0 0 270)
			(unlocked yes)
			(layer "F.Fab")
			(hide yes)
			(effects
				(font
					(size 1 1)
					(thickness 0.15)
				)
			)
		)
		(property "MPN" "GRM188R60J226MEA0D"
			(at 0 0 270)
			(unlocked yes)
			(layer "F.Fab")
			(hide yes)
			(effects
				(font
					(size 1 1)
					(thickness 0.15)
				)
			)
		)
		(property "Val" "22u"
			(at 0 0 270)
			(unlocked yes)
			(layer "F.Fab")
			(hide yes)
			(effects
				(font
					(size 1 1)
					(thickness 0.15)
				)
			)
		)
		(property "License" "Apache-2.0"
			(at 0 0 270)
			(unlocked yes)
			(layer "F.Fab")
			(hide yes)
			(effects
				(font
					(size 1 1)
					(thickness 0.15)
				)
			)
		)
		(property "Author" "Antmicro"
			(at 0 0 270)
			(unlocked yes)
			(layer "F.Fab")
			(hide yes)
			(effects
				(font
					(size 1 1)
					(thickness 0.15)
				)
			)
		)
		(property "Voltage" ""
			(at 0 0 270)
			(unlocked yes)
			(layer "F.Fab")
			(hide yes)
			(effects
				(font
					(size 1 1)
					(thickness 0.15)
				)
			)
		)
		(property "Dielectric" ""
			(at 0 0 270)
			(unlocked yes)
			(layer "F.Fab")
			(hide yes)
			(effects
				(font
					(size 1 1)
					(thickness 0.15)
				)
			)
		)
		(sheetname "/Supply/DC-DC IO/")
		(sheetfile "dc-dc-io.kicad_sch")
		(attr smd)
		(fp_line
			(start -0.15 0.4)
			(end 0.15 0.4)
			(stroke
				(width 0.15)
				(type solid)
			)
			(layer "F.SilkS")
		)
		(fp_line
			(start -0.15 -0.4)
			(end 0.15 -0.4)
			(stroke
				(width 0.15)
				(type solid)
			)
			(layer "F.SilkS")
		)
		(fp_rect
			(start -1.25 -0.65)
			(end 1.25 0.65)
			(stroke
				(width 0.05)
				(type solid)
			)
			(fill no)
			(layer "F.CrtYd")
		)
		(fp_rect
			(start -0.8 -0.4)
			(end 0.8 0.4)
			(stroke
				(width 0.15)
				(type solid)
			)
			(fill no)
			(layer "F.Fab")
		)
		(fp_text user "Author: Antmicro"
			(at -1.682 4.894 270)
			(layer "F.Fab")
			(effects
				(font
					(size 0.7 0.7)
					(thickness 0.15)
				)
				(justify left bottom)
			)
		)
		(fp_text user "${REFERENCE}"
			(at -1.682 3.895 270)
			(layer "F.Fab")
			(effects
				(font
					(size 0.7 0.7)
					(thickness 0.15)
				)
				(justify left bottom)
			)
		)
		(fp_text user "License: Apache-2.0"
			(at -1.682 5.895 270)
			(layer "F.Fab")
			(effects
				(font
					(size 0.7 0.7)
					(thickness 0.15)
				)
				(justify left bottom)
			)
		)
		(pad "1" smd roundrect
			(at -0.7 0 270)
			(size 0.8 1)
			(layers "F.Cu" "F.Mask" "F.Paste")
			(roundrect_rratio 0.2)
			(net 1 "GND")
			(pintype "passive")
		)
		(pad "2" smd roundrect
			(at 0.7 0 270)
			(size 0.8 1)
			(layers "F.Cu" "F.Mask" "F.Paste")
			(roundrect_rratio 0.2)
			(net 45 "/Supply/DC-DC IO/3V3_local")
			(pintype "passive")
		)
	)
	(footprint "antmicro-footprints:R_0402_1005Metric"
		(layer "F.Cu")
		(at 121.681 168.3125 90)
		(descr "Resistor SMD 0402")
		(tags "resistor SMD 0402")
		(property "Reference" "R219"
			(at -3.825 0.619 90)
			(layer "F.SilkS")
			(effects
				(font
					(size 0.7 0.7)
					(thickness 0.15)
				)
				(justify left bottom)
			)
		)
		(property "Value" "R_64k9_0402"
			(at -1.011843 1.772047 90)
			(layer "F.Fab")
			(effects
				(font
					(size 0.7 0.7)
					(thickness 0.15)
				)
				(justify left bottom)
			)
		)
		(property "Datasheet" "https://www.bourns.com/docs/product-datasheets/cr.pdf"
			(at 0 0 90)
			(layer "F.Fab")
			(hide yes)
			(effects
				(font
					(size 1.27 1.27)
					(thickness 0.15)
				)
			)
		)
		(property "MPN" "CR0402-FX-6492GLF"
			(at 0 0 90)
			(unlocked yes)
			(layer "F.Fab")
			(hide yes)
			(effects
				(font
					(size 1 1)
					(thickness 0.15)
				)
			)
		)
		(property "Manufacturer" "Bourns"
			(at 0 0 90)
			(unlocked yes)
			(layer "F.Fab")
			(hide yes)
			(effects
				(font
					(size 1 1)
					(thickness 0.15)
				)
			)
		)
		(property "License" "Apache-2.0"
			(at 0 0 90)
			(unlocked yes)
			(layer "F.Fab")
			(hide yes)
			(effects
				(font
					(size 1 1)
					(thickness 0.15)
				)
			)
		)
		(property "Author" "Antmicro"
			(at 0 0 90)
			(unlocked yes)
			(layer "F.Fab")
			(hide yes)
			(effects
				(font
					(size 1 1)
					(thickness 0.15)
				)
			)
		)
		(property "Val" "64k9"
			(at 0 0 90)
			(unlocked yes)
			(layer "F.Fab")
			(hide yes)
			(effects
				(font
					(size 1 1)
					(thickness 0.15)
				)
			)
		)
		(property "Tolerance" "1%"
			(at 0 0 90)
			(unlocked yes)
			(layer "F.Fab")
			(hide yes)
			(effects
				(font
					(size 1 1)
					(thickness 0.15)
				)
			)
		)
		(sheetname "/HDMI + SD Card/")
		(sheetfile "hdmi-sd-card.kicad_sch")
		(attr smd)
		(fp_rect
			(start -0.925 -0.47)
			(end 0.925 0.47)
			(stroke
				(width 0.05)
				(type default)
			)
			(fill no)
			(layer "F.CrtYd")
		)
		(fp_rect
			(start -0.5 -0.25)
			(end 0.5 0.25)
			(stroke
				(width 0.15)
				(type solid)
			)
			(fill no)
			(layer "F.Fab")
		)
		(fp_text user "License: Apache-2.0"
			(at -0.95 5.169 90)
			(layer "F.Fab")
			(effects
				(font
					(size 0.7 0.7)
					(thickness 0.15)
				)
				(justify left bottom)
			)
		)
		(fp_text user "Author: Antmicro"
			(at -0.95 4.169 90)
			(layer "F.Fab")
			(effects
				(font
					(size 0.7 0.7)
					(thickness 0.15)
				)
				(justify left bottom)
			)
		)
		(fp_text user "${REFERENCE}"
			(at -0.95 3.168 90)
			(layer "F.Fab")
			(effects
				(font
					(size 0.7 0.7)
					(thickness 0.15)
				)
				(justify left bottom)
			)
		)
		(pad "1" smd roundrect
			(at -0.48 0 90)
			(size 0.59 0.64)
			(layers "F.Cu" "F.Mask" "F.Paste")
			(roundrect_rratio 0.25)
			(net 1 "GND")
			(pintype "passive")
		)
		(pad "2" smd roundrect
			(at 0.48 0 90)
			(size 0.59 0.64)
			(layers "F.Cu" "F.Mask" "F.Paste")
			(roundrect_rratio 0.25)
			(net 738 "/HDMI + SD Card/~{HDMI_SEL}")
			(pintype "passive")
		)
	)
	(footprint "antmicro-footprints:C_0402_1005Metric"
		(layer "F.Cu")
		(at 126.306 176.022 90)
		(descr "Capacitor SMD 0402")
		(tags "capacitor SMD 0402")
		(property "Reference" "C283"
			(at 1.2 0.49 90)
			(layer "F.SilkS")
			(effects
				(font
					(size 0.7 0.7)
					(thickness 0.15)
				)
				(justify left bottom)
			)
		)
		(property "Value" "C_100n_0402"
			(at -1.022927 2.155213 90)
			(layer "F.Fab")
			(effects
				(font
					(size 0.7 0.7)
					(thickness 0.15)
				)
				(justify left bottom)
			)
		)
		(property "Datasheet" "https://www.murata.com/products/productdetail?partno=GRM155R61H104KE14%23"
			(at 0 0 90)
			(layer "F.Fab")
			(hide yes)
			(effects
				(font
					(size 1.27 1.27)
					(thickness 0.15)
				)
			)
		)
		(property "MPN" "GRM155R61H104KE14D"
			(at 0 0 90)
			(unlocked yes)
			(layer "F.Fab")
			(hide yes)
			(effects
				(font
					(size 1 1)
					(thickness 0.15)
				)
			)
		)
		(property "Manufacturer" "Murata"
			(at 0 0 90)
			(unlocked yes)
			(layer "F.Fab")
			(hide yes)
			(effects
				(font
					(size 1 1)
					(thickness 0.15)
				)
			)
		)
		(property "License" "Apache-2.0"
			(at 0 0 90)
			(unlocked yes)
			(layer "F.Fab")
			(hide yes)
			(effects
				(font
					(size 1 1)
					(thickness 0.15)
				)
			)
		)
		(property "Author" "Antmicro"
			(at 0 0 90)
			(unlocked yes)
			(layer "F.Fab")
			(hide yes)
			(effects
				(font
					(size 1 1)
					(thickness 0.15)
				)
			)
		)
		(property "Val" "100n"
			(at 0 0 90)
			(unlocked yes)
			(layer "F.Fab")
			(hide yes)
			(effects
				(font
					(size 1 1)
					(thickness 0.15)
				)
			)
		)
		(property "Voltage" "50V"
			(at 0 0 90)
			(unlocked yes)
			(layer "F.Fab")
			(hide yes)
			(effects
				(font
					(size 1 1)
					(thickness 0.15)
				)
			)
		)
		(property "Dielectric" "X5R"
			(at 0 0 90)
			(unlocked yes)
			(layer "F.Fab")
			(hide yes)
			(effects
				(font
					(size 1 1)
					(thickness 0.15)
				)
			)
		)
		(property "Public" ""
			(at 0 0 90)
			(unlocked yes)
			(layer "F.Fab")
			(hide yes)
			(effects
				(font
					(size 1 1)
					(thickness 0.15)
				)
			)
		)
		(sheetname "/HDMI + SD Card/")
		(sheetfile "hdmi-sd-card.kicad_sch")
		(attr smd)
		(fp_rect
			(start -0.925 -0.47)
			(end 0.925 0.47)
			(stroke
				(width 0.05)
				(type default)
			)
			(fill no)
			(layer "F.CrtYd")
		)
		(fp_line
			(start 0.504 -0.25)
			(end 0.504 0.248)
			(stroke
				(width 0.15)
				(type solid)
			)
			(layer "F.Fab")
		)
		(fp_line
			(start -0.494 -0.25)
			(end 0.504 -0.25)
			(stroke
				(width 0.15)
				(type solid)
			)
			(layer "F.Fab")
		)
		(fp_line
			(start 0.504 0.248)
			(end -0.494 0.248)
			(stroke
				(width 0.15)
				(type solid)
			)
			(layer "F.Fab")
		)
		(fp_line
			(start -0.494 0.248)
			(end -0.494 -0.25)
			(stroke
				(width 0.15)
				(type solid)
			)
			(layer "F.Fab")
		)
		(fp_text user "Author: Antmicro"
			(at -0.939 3.399 90)
			(layer "F.Fab")
			(effects
				(font
					(size 0.7 0.7)
					(thickness 0.15)
				)
				(justify left bottom)
			)
		)
		(fp_text user "${REFERENCE}"
			(at -0.939 4.599 90)
			(layer "F.Fab")
			(effects
				(font
					(size 0.7 0.7)
					(thickness 0.15)
				)
				(justify left bottom)
			)
		)
		(fp_text user "License: Apache-2.0"
			(at -0.939 5.799 90)
			(layer "F.Fab")
			(effects
				(font
					(size 0.7 0.7)
					(thickness 0.15)
				)
				(justify left bottom)
			)
		)
		(pad "1" smd roundrect
			(at -0.48 0 90)
			(size 0.59 0.64)
			(layers "F.Cu" "F.Mask" "F.Paste")
			(roundrect_rratio 0.25)
			(net 810 "/HDMI + SD Card/HDMI_VDD")
			(pintype "passive")
		)
		(pad "2" smd roundrect
			(at 0.48 0 90)
			(size 0.59 0.64)
			(layers "F.Cu" "F.Mask" "F.Paste")
			(roundrect_rratio 0.25)
			(net 1 "GND")
			(pintype "passive")
		)
	)
	(footprint "antmicro-footprints:C_0402_1005Metric"
		(layer "F.Cu")
		(at 252.92 182.078 -90)
		(descr "Capacitor SMD 0402")
		(tags "capacitor SMD 0402")
		(property "Reference" "C325"
			(at -1.878 2.57 90)
			(layer "F.SilkS")
			(effects
				(font
					(size 0.7 0.7)
					(thickness 0.15)
				)
				(justify right bottom)
			)
		)
		(property "Value" "C_100n_0402"
			(at -1.022927 2.155213 90)
			(layer "F.Fab")
			(effects
				(font
					(size 0.7 0.7)
					(thickness 0.15)
				)
				(justify right bottom)
			)
		)
		(property "Datasheet" "https://www.murata.com/products/productdetail?partno=GRM155R61H104KE14%23"
			(at 0 0 270)
			(layer "F.Fab")
			(hide yes)
			(effects
				(font
					(size 1.27 1.27)
					(thickness 0.15)
				)
			)
		)
		(property "MPN" "GRM155R61H104KE14D"
			(at 0 0 270)
			(unlocked yes)
			(layer "F.Fab")
			(hide yes)
			(effects
				(font
					(size 1 1)
					(thickness 0.15)
				)
			)
		)
		(property "Manufacturer" "Murata"
			(at 0 0 270)
			(unlocked yes)
			(layer "F.Fab")
			(hide yes)
			(effects
				(font
					(size 1 1)
					(thickness 0.15)
				)
			)
		)
		(property "License" "Apache-2.0"
			(at 0 0 270)
			(unlocked yes)
			(layer "F.Fab")
			(hide yes)
			(effects
				(font
					(size 1 1)
					(thickness 0.15)
				)
			)
		)
		(property "Author" "Antmicro"
			(at 0 0 270)
			(unlocked yes)
			(layer "F.Fab")
			(hide yes)
			(effects
				(font
					(size 1 1)
					(thickness 0.15)
				)
			)
		)
		(property "Val" "100n"
			(at 0 0 270)
			(unlocked yes)
			(layer "F.Fab")
			(hide yes)
			(effects
				(font
					(size 1 1)
					(thickness 0.15)
				)
			)
		)
		(property "Voltage" "50V"
			(at 0 0 270)
			(unlocked yes)
			(layer "F.Fab")
			(hide yes)
			(effects
				(font
					(size 1 1)
					(thickness 0.15)
				)
			)
		)
		(property "Dielectric" "X5R"
			(at 0 0 270)
			(unlocked yes)
			(layer "F.Fab")
			(hide yes)
			(effects
				(font
					(size 1 1)
					(thickness 0.15)
				)
			)
		)
		(sheetname "/I^{2}C + I3C/")
		(sheetfile "i2c.kicad_sch")
		(attr smd)
		(fp_rect
			(start -0.925 -0.47)
			(end 0.925 0.47)
			(stroke
				(width 0.05)
				(type default)
			)
			(fill no)
			(layer "F.CrtYd")
		)
		(fp_line
			(start -0.494 0.248)
			(end -0.494 -0.25)
			(stroke
				(width 0.15)
				(type solid)
			)
			(layer "F.Fab")
		)
		(fp_line
			(start 0.504 0.248)
			(end -0.494 0.248)
			(stroke
				(width 0.15)
				(type solid)
			)
			(layer "F.Fab")
		)
		(fp_line
			(start -0.494 -0.25)
			(end 0.504 -0.25)
			(stroke
				(width 0.15)
				(type solid)
			)
			(layer "F.Fab")
		)
		(fp_line
			(start 0.504 -0.25)
			(end 0.504 0.248)
			(stroke
				(width 0.15)
				(type solid)
			)
			(layer "F.Fab")
		)
		(fp_text user "Author: Antmicro"
			(at -0.939 3.399 270)
			(layer "F.Fab")
			(effects
				(font
					(size 0.7 0.7)
					(thickness 0.15)
				)
				(justify left bottom)
			)
		)
		(fp_text user "License: Apache-2.0"
			(at -0.939 5.799 270)
			(layer "F.Fab")
			(effects
				(font
					(size 0.7 0.7)
					(thickness 0.15)
				)
				(justify left bottom)
			)
		)
		(fp_text user "${REFERENCE}"
			(at -0.939 4.599 270)
			(layer "F.Fab")
			(effects
				(font
					(size 0.7 0.7)
					(thickness 0.15)
				)
				(justify left bottom)
			)
		)
		(pad "1" smd roundrect
			(at -0.48 0 270)
			(size 0.59 0.64)
			(layers "F.Cu" "F.Mask" "F.Paste")
			(roundrect_rratio 0.25)
			(net 1 "GND")
			(pintype "passive")
		)
		(pad "2" smd roundrect
			(at 0.48 0 270)
			(size 0.59 0.64)
			(layers "F.Cu" "F.Mask" "F.Paste")
			(roundrect_rratio 0.25)
			(net 664 "Net-(C325-Pad2)")
			(pintype "passive")
		)
	)
	(footprint "antmicro-footprints:SOT-23-6"
		(layer "F.Cu")
		(at 153.21 191.185)
		(property "Reference" "U18"
			(at 1.59 1.715 0)
			(layer "F.SilkS")
			(effects
				(font
					(size 0.7 0.7)
					(thickness 0.15)
				)
				(justify left bottom)
			)
		)
		(property "Value" "LTC4412IS6"
			(at -1.75 2.75 0)
			(layer "F.Fab")
			(effects
				(font
					(size 0.7 0.7)
					(thickness 0.15)
				)
				(justify left bottom)
			)
		)
		(property "Datasheet" "https://www.mouser.com/datasheet/2/308/NCV8187_D-1813214.pdf"
			(at 0 0 0)
			(layer "F.Fab")
			(hide yes)
			(effects
				(font
					(size 1.27 1.27)
					(thickness 0.15)
				)
			)
		)
		(property "MPN" "LTC4412IS6#TRMPBF"
			(at 0 0 0)
			(unlocked yes)
			(layer "F.Fab")
			(hide yes)
			(effects
				(font
					(size 1 1)
					(thickness 0.15)
				)
			)
		)
		(property "Manufacturer" "Analog Devices"
			(at 0 0 0)
			(unlocked yes)
			(layer "F.Fab")
			(hide yes)
			(effects
				(font
					(size 1 1)
					(thickness 0.15)
				)
			)
		)
		(property "Author" "Antmicro"
			(at 0 0 0)
			(unlocked yes)
			(layer "F.Fab")
			(hide yes)
			(effects
				(font
					(size 1 1)
					(thickness 0.15)
				)
			)
		)
		(property "License" "Apache-2.0"
			(at 0 0 0)
			(unlocked yes)
			(layer "F.Fab")
			(hide yes)
			(effects
				(font
					(size 1 1)
					(thickness 0.15)
				)
			)
		)
		(sheetname "/Supply/")
		(sheetfile "supply.kicad_sch")
		(attr smd)
		(fp_line
			(start -1.45 -0.757)
			(end -1.45 -0.457)
			(stroke
				(width 0.12)
				(type solid)
			)
			(layer "F.SilkS")
		)
		(fp_line
			(start -1.45 0.643)
			(end -1.45 0.343)
			(stroke
				(width 0.12)
				(type solid)
			)
			(layer "F.SilkS")
		)
		(fp_line
			(start -1.3 -0.757)
			(end -1.45 -0.757)
			(stroke
				(width 0.12)
				(type solid)
			)
			(layer "F.SilkS")
		)
		(fp_line
			(start 1.3 -0.757)
			(end 1.45 -0.757)
			(stroke
				(width 0.12)
				(type solid)
			)
			(layer "F.SilkS")
		)
		(fp_line
			(start 1.3 0.643)
			(end 1.45 0.643)
			(stroke
				(width 0.12)
				(type solid)
			)
			(layer "F.SilkS")
		)
		(fp_line
			(start 1.45 -0.757)
			(end 1.45 -0.457)
			(stroke
				(width 0.12)
				(type solid)
			)
			(layer "F.SilkS")
		)
		(fp_line
			(start 1.45 0.643)
			(end 1.45 0.343)
			(stroke
				(width 0.12)
				(type solid)
			)
			(layer "F.SilkS")
		)
		(fp_rect
			(start -1.55 -1.85)
			(end 1.55 1.75)
			(stroke
				(width 0.05)
				(type solid)
			)
			(fill no)
			(layer "F.CrtYd")
		)
		(fp_line
			(start -1.5 -0.757)
			(end 1.5 -0.757)
			(stroke
				(width 0.1)
				(type solid)
			)
			(layer "F.Fab")
		)
		(fp_line
			(start -1.5 0.643)
			(end -1.5 -0.757)
			(stroke
				(width 0.1)
				(type solid)
			)
			(layer "F.Fab")
		)
		(fp_line
			(start 1.5 -0.757)
			(end 1.5 0.643)
			(stroke
				(width 0.1)
				(type solid)
			)
			(layer "F.Fab")
		)
		(fp_line
			(start 1.5 0.643)
			(end -1.5 0.643)
			(stroke
				(width 0.1)
				(type solid)
			)
			(layer "F.Fab")
		)
		(fp_text user "."
			(at -1.4 1.2 0)
			(layer "F.SilkS")
			(effects
				(font
					(size 1 1)
					(thickness 0.15)
				)
			)
		)
		(fp_text user "License: Apache-2.0"
			(at -1.75 6.5 0)
			(layer "F.Fab")
			(effects
				(font
					(size 0.7 0.7)
					(thickness 0.15)
				)
				(justify left bottom)
			)
		)
		(fp_text user "Author: Antmicro"
			(at -1.829 5.25 0)
			(layer "F.Fab")
			(effects
				(font
					(size 0.7 0.7)
					(thickness 0.15)
				)
				(justify left bottom)
			)
		)
		(fp_text user "${REFERENCE}"
			(at -1.75 4 0)
			(layer "F.Fab")
			(effects
				(font
					(size 0.7 0.7)
					(thickness 0.15)
				)
				(justify left bottom)
			)
		)
		(pad "1" smd roundrect
			(at -0.954 1.1)
			(size 0.55 1)
			(layers "F.Cu" "F.Mask" "F.Paste")
			(roundrect_rratio 0.15)
			(net 324 "/Supply/12V_PCIE_fused")
			(pinfunction "IN")
			(pintype "power_in")
		)
		(pad "2" smd roundrect
			(at -0.003 1.1)
			(size 0.55 1)
			(layers "F.Cu" "F.Mask" "F.Paste")
			(roundrect_rratio 0.15)
			(net 1 "GND")
			(pinfunction "GND")
			(pintype "power_in")
		)
		(pad "3" smd roundrect
			(at 0.947 1.1)
			(size 0.55 1)
			(layers "F.Cu" "F.Mask" "F.Paste")
			(roundrect_rratio 0.15)
			(net 1 "GND")
			(pinfunction "CTL")
			(pintype "input")
		)
		(pad "4" smd roundrect
			(at 0.947 -1.214)
			(size 0.55 1)
			(layers "F.Cu" "F.Mask" "F.Paste")
			(roundrect_rratio 0.15)
			(net 429 "unconnected-(U18-STAT-Pad4)")
			(pinfunction "STAT")
			(pintype "output+no_connect")
		)
		(pad "5" smd roundrect
			(at -0.003 -1.214)
			(size 0.55 1)
			(layers "F.Cu" "F.Mask" "F.Paste")
			(roundrect_rratio 0.15)
			(net 285 "Net-(Q13-G)")
			(pinfunction "GATE")
			(pintype "output")
		)
		(pad "6" smd roundrect
			(at -0.954 -1.214)
			(size 0.55 1)
			(layers "F.Cu" "F.Mask" "F.Paste")
			(roundrect_rratio 0.15)
			(net 35 "VDC")
			(pinfunction "SENSE")
			(pintype "input")
		)
	)
)
